(kicad_pcb
	(version 20260206)
	(generator "pcbnew")
	(generator_version "10.0")
	(general
		(thickness 1.6)
		(legacy_teardrops no)
	)
	(paper "A4")
	(title_block
		(title "baseboard — 13948-1b.1110WZS1818.brd")
		(comment 1 "Honey Badger (Wiwynn) / footprints 1620-1625 of 2523")
	)
	(layers
		(0 "F.Cu" signal "TOP")
		(4 "In1.Cu" signal "L2GND")
		(6 "In2.Cu" signal "L3")
		(8 "In3.Cu" signal "L4VCC")
		(10 "In4.Cu" signal "L5VCC")
		(12 "In5.Cu" signal "L6")
		(14 "In6.Cu" signal "L7GND")
		(2 "B.Cu" signal "BOTTOM")
		(9 "F.Adhes" user "F.Adhesive")
		(11 "B.Adhes" user "B.Adhesive")
		(13 "F.Paste" user "Package Geometry/Pastemask Top")
		(15 "B.Paste" user "Package Geometry/Pastemask Bottom")
		(5 "F.SilkS" user "Ref Des/Silkscreen Top")
		(7 "B.SilkS" user "Ref Des/Silkscreen Bottom")
		(1 "F.Mask" user "Board Geometry/Soldermask Top")
		(3 "B.Mask" user "Board Geometry/Soldermask Bottom")
		(17 "Dwgs.User" user "User.Drawings")
		(19 "Cmts.User" user "User.Comments")
		(21 "Eco1.User" user "User.Eco1")
		(23 "Eco2.User" user "User.Eco2")
		(25 "Edge.Cuts" user "Board Geometry/Outline")
		(27 "Margin" user)
		(31 "F.CrtYd" user "Package Geometry/Place Bound Top")
		(29 "B.CrtYd" user "Package Geometry/Place Bound Bottom")
		(35 "F.Fab" user "Ref Des/Assembly Top")
		(33 "B.Fab" user "Ref Des/Assembly Bottom")
	)
	(footprint ""
		(layer "F.Cu")
		(at 350.484948 -28.90012 180)
		(property "Reference" "SW3"
			(at 0 0 180)
			(layer "F.SilkS")
			(hide yes)
			(effects
				(font
					(size 1.27 1.27)
				)
			)
		)
		(property "Value" "PUSH-SW132-GP"
			(at -4.9657 -6.1341 180)
			(unlocked yes)
			(layer "F.Fab")
			(hide yes)
			(effects
				(font
					(size 1.016 1.016)
					(thickness 0.1524)
				)
			)
		)
		(property "Device Type" "PTCFGP2-Q-TR"
			(at -4.9657 -7.6581 180)
			(unlocked yes)
			(layer "F.Fab")
			(hide yes)
			(effects
				(font
					(size 1.016 1.016)
					(thickness 0.1524)
				)
			)
		)
		(duplicate_pad_numbers_are_jumpers no)
		(fp_line
			(start 3.556 1.6002)
			(end 2.7178 1.6002)
			(stroke
				(width 0.1524)
				(type default)
			)
			(layer "F.SilkS")
		)
		(fp_line
			(start 3.556 -2.0066)
			(end 3.556 1.6002)
			(stroke
				(width 0.1524)
				(type default)
			)
			(layer "F.SilkS")
		)
		(fp_line
			(start 2.7178 2.7686)
			(end 1.4986 2.7686)
			(stroke
				(width 0.1524)
				(type default)
			)
			(layer "F.SilkS")
		)
		(fp_line
			(start 2.7178 1.6002)
			(end 2.7178 2.7686)
			(stroke
				(width 0.1524)
				(type default)
			)
			(layer "F.SilkS")
		)
		(fp_line
			(start 1.4986 2.7686)
			(end 1.4986 2.0066)
			(stroke
				(width 0.1524)
				(type default)
			)
			(layer "F.SilkS")
		)
		(fp_line
			(start 1.4986 2.0066)
			(end -3.556 2.0066)
			(stroke
				(width 0.1524)
				(type default)
			)
			(layer "F.SilkS")
		)
		(fp_line
			(start -3.556 2.0066)
			(end -3.556 -2.0066)
			(stroke
				(width 0.1524)
				(type default)
			)
			(layer "F.SilkS")
		)
		(fp_line
			(start -3.556 -2.0066)
			(end 3.556 -2.0066)
			(stroke
				(width 0.1524)
				(type default)
			)
			(layer "F.SilkS")
		)
		(fp_line
			(start -3.6576 -0.6604)
			(end -3.6576 -1.0414)
			(stroke
				(width 0.3302)
				(type default)
			)
			(layer "F.SilkS")
		)
		(fp_poly
			(pts
				(xy -4.2545 -0.2159) (xy -4.2545 -1.4859) (xy -3.6195 -0.8509)
			)
			(stroke
				(width 0)
				(type default)
			)
			(fill yes)
			(layer "F.SilkS")
		)
		(fp_poly
			(pts
				(xy 1.7526 2.2606) (xy 1.7526 1.7526) (xy -2.3495 1.7526) (xy -2.3495 1.1049) (xy -2.9464 1.1049)
				(xy -2.9464 -1.1049) (xy -2.3495 -1.1049) (xy -2.3495 -1.7526) (xy 2.3495 -1.7526) (xy 2.3495 -1.1049)
				(xy 2.9464 -1.1049) (xy 2.9464 1.1049) (xy 2.3495 1.1049) (xy 2.3495 2.2606)
			)
			(stroke
				(width 0)
				(type default)
			)
			(fill no)
			(layer "F.CrtYd")
		)
		(fp_poly
			(pts
				(xy 1.2446 3.0226) (xy 1.2446 2.2606) (xy -3.81 2.2606) (xy -3.81 -2.2606) (xy -1.4097 -2.2606)
				(xy -1.4097 -1.752854) (xy -2.349754 -1.752854) (xy -2.349754 -1.105154) (xy -2.946654 -1.105154)
				(xy -2.946654 1.105154) (xy -2.349754 1.105154) (xy -2.349754 1.752854) (xy 1.752346 1.752854) (xy 1.752346 2.2606)
				(xy 2.349754 2.2606) (xy 2.349754 1.105154) (xy 2.946654 1.105154) (xy 2.946654 -1.105154) (xy 2.349754 -1.105154)
				(xy 2.349754 -1.752854) (xy -1.397 -1.752854) (xy -1.397 -2.2606) (xy 3.81 -2.2606) (xy 3.81 1.8542)
				(xy 2.9718 1.8542) (xy 2.9718 3.0226)
			)
			(stroke
				(width 0)
				(type default)
			)
			(fill no)
			(layer "F.CrtYd")
		)
		(fp_poly
			(pts
				(xy 1.2446 3.0226) (xy 1.2446 2.2606) (xy -3.81 2.2606) (xy -3.81 -2.2606) (xy 3.81 -2.2606) (xy 3.81 1.8542)
				(xy 2.9718 1.8542) (xy 2.9718 3.0226)
			)
			(stroke
				(width 0)
				(type default)
			)
			(fill no)
			(layer "F.Fab")
		)
		(pad "" np_thru_hole circle
			(at 0 -1.35001 180)
			(size 0.254 0.254)
			(drill 0.8128)
			(layers "*.Cu" "*.Mask")
			(clearance 0.635)
			(thermal_gap 0.635)
		)
		(pad "" np_thru_hole circle
			(at 0 1.35001 180)
			(size 0.254 0.254)
			(drill 0.8128)
			(layers "*.Cu" "*.Mask")
			(clearance 0.635)
			(thermal_gap 0.635)
		)
		(pad "1" smd rect
			(at -2.576068 -0.85471 180)
			(size 1.4478 0.9906)
			(layers "F.Cu" "F.Mask" "F.Paste")
			(net "GND")
		)
		(pad "2" smd rect
			(at -2.576068 0.85471 180)
			(size 1.4478 0.9906)
			(layers "F.Cu" "F.Mask" "F.Paste")
			(net "SHUTDOWN_RELEASE")
		)
		(pad "3" smd rect
			(at 2.576068 -0.85471 180)
			(size 1.4478 0.9906)
			(layers "F.Cu" "F.Mask" "F.Paste")
			(net "GND")
		)
		(pad "4" smd rect
			(at 2.576068 0.85471 180)
			(size 1.4478 0.9906)
			(layers "F.Cu" "F.Mask" "F.Paste")
			(net "SHUTDOWN_RELEASE")
		)
		(pad "5" smd rect
			(at 2.10566 2.13106 180)
			(size 0.7112 0.762)
			(layers "F.Cu" "F.Mask" "F.Paste")
			(net "Net_213")
		)
		(zone
			(layers "F.Cu" "B.Cu" "In1.Cu" "In2.Cu" "In3.Cu" "In4.Cu" "In5.Cu" "In6.Cu")
			(hatch none 0.5)
			(connect_pads
				(clearance 0)
			)
			(min_thickness 0.25)
			(keepout
				(tracks not_allowed)
				(vias allowed)
				(pads allowed)
				(copperpour not_allowed)
				(footprints allowed)
			)
			(placement
				(enabled no)
				(sheetname "")
			)
			(fill
				(thermal_gap 0.5)
				(thermal_bridge_width 0.5)
				(island_removal_mode 0)
			)
			(polygon
				(pts
					(arc
						(start 351.196148 -30.25013)
						(mid 349.773748 -30.25013)
						(end 351.196148 -30.25013)
					)
				)
			)
		)
		(zone
			(layers "F.Cu" "B.Cu" "In1.Cu" "In2.Cu" "In3.Cu" "In4.Cu" "In5.Cu" "In6.Cu")
			(hatch none 0.5)
			(connect_pads
				(clearance 0)
			)
			(min_thickness 0.25)
			(keepout
				(tracks not_allowed)
				(vias allowed)
				(pads allowed)
				(copperpour not_allowed)
				(footprints allowed)
			)
			(placement
				(enabled no)
				(sheetname "")
			)
			(fill
				(thermal_gap 0.5)
				(thermal_bridge_width 0.5)
				(island_removal_mode 0)
			)
			(polygon
				(pts
					(arc
						(start 351.196148 -27.55011)
						(mid 349.773748 -27.55011)
						(end 351.196148 -27.55011)
					)
				)
			)
		)
	)
	(footprint ""
		(layer "F.Cu")
		(at 95.26397 -118.3005 180)
		(property "Reference" "SR750"
			(at 0 0 180)
			(layer "F.SilkS")
			(hide yes)
			(effects
				(font
					(size 1.27 1.27)
				)
			)
		)
		(property "Value" "4K7R2F-GP"
			(at 0.064008 -3.993896 180)
			(unlocked yes)
			(layer "F.Fab")
			(hide yes)
			(effects
				(font
					(size 1.016 1.016)
					(thickness 0.1524)
				)
			)
		)
		(property "Device Type" "R402H16"
			(at 0.064008 -5.517896 180)
			(unlocked yes)
			(layer "F.Fab")
			(hide yes)
			(effects
				(font
					(size 1.016 1.016)
					(thickness 0.1524)
				)
			)
		)
		(duplicate_pad_numbers_are_jumpers no)
		(fp_line
			(start 0.508 -0.9398)
			(end -0.508 -0.9398)
			(stroke
				(width 0.1524)
				(type default)
			)
			(layer "F.SilkS")
		)
		(fp_line
			(start -0.508 -0.9398)
			(end -0.508 0.9398)
			(stroke
				(width 0.1524)
				(type default)
			)
			(layer "F.SilkS")
		)
		(fp_rect
			(start -0.508 0.9398)
			(end 0.508 -0.9398)
			(stroke
				(width 0)
				(type default)
			)
			(fill no)
			(layer "F.CrtYd")
		)
		(fp_rect
			(start -0.508 0.9398)
			(end 0.508 -0.9398)
			(stroke
				(width 0)
				(type default)
			)
			(fill no)
			(layer "F.Fab")
		)
		(pad "1" smd custom
			(at 0 -0.4445 180)
			(size 0.1397 0.1397)
			(layers "F.Cu" "F.Mask" "F.Paste")
			(net "SIO_LOAD_OUT")
			(options
				(clearance outline)
				(anchor circle)
			)
			(primitives
				(gr_poly
					(pts
						(arc
							(start -0.1778 -0.2794)
							(mid -0.249642 -0.249642)
							(end -0.2794 -0.1778)
						)
						(arc
							(start -0.2794 0.1778)
							(mid -0.249642 0.249642)
							(end -0.1778 0.2794)
						)
						(arc
							(start 0.1778 0.2794)
							(mid 0.249642 0.249642)
							(end 0.2794 0.1778)
						)
						(arc
							(start 0.2794 -0.1778)
							(mid 0.249642 -0.249642)
							(end 0.1778 -0.2794)
						)
					)
					(width 0)
					(fill yes)
				)
			)
		)
		(pad "2" smd custom
			(at 0 0.4445 180)
			(size 0.1397 0.1397)
			(layers "F.Cu" "F.Mask" "F.Paste")
			(net "P1V8_E")
			(options
				(clearance outline)
				(anchor circle)
			)
			(primitives
				(gr_poly
					(pts
						(arc
							(start -0.1778 -0.2794)
							(mid -0.249642 -0.249642)
							(end -0.2794 -0.1778)
						)
						(arc
							(start -0.2794 0.1778)
							(mid -0.249642 0.249642)
							(end -0.1778 0.2794)
						)
						(arc
							(start 0.1778 0.2794)
							(mid 0.249642 0.249642)
							(end 0.2794 0.1778)
						)
						(arc
							(start 0.2794 -0.1778)
							(mid 0.249642 -0.249642)
							(end 0.1778 -0.2794)
						)
					)
					(width 0)
					(fill yes)
				)
			)
		)
	)
	(footprint ""
		(layer "F.Cu")
		(at 216.281 -93.98 -90)
		(property "Reference" "PC140"
			(at 0 0 270)
			(layer "F.SilkS")
			(hide yes)
			(effects
				(font
					(size 1.27 1.27)
				)
			)
		)
		(property "Value" "SC10U6D3V5KX-1GP"
			(at -0.0762 -6.1214 270)
			(unlocked yes)
			(layer "F.Fab")
			(hide yes)
			(effects
				(font
					(size 1.016 1.016)
					(thickness 0.1524)
				)
			)
		)
		(property "Device Type" "C805H54"
			(at -0.0762 -8.1534 270)
			(unlocked yes)
			(layer "F.Fab")
			(hide yes)
			(effects
				(font
					(size 1.016 1.016)
					(thickness 0.1524)
				)
			)
		)
		(duplicate_pad_numbers_are_jumpers no)
		(fp_line
			(start 0.635 0)
			(end -0.635 0)
			(stroke
				(width 0.508)
				(type default)
			)
			(layer "F.SilkS")
		)
		(fp_rect
			(start -0.9652 1.778)
			(end 0.9652 -1.778)
			(stroke
				(width 0)
				(type default)
			)
			(fill no)
			(layer "F.CrtYd")
		)
		(fp_poly
			(pts
				(xy -0.9652 -1.778) (xy 0.9652 -1.778) (xy 0.9652 1.778) (xy -0.9652 1.778)
			)
			(stroke
				(width 0)
				(type default)
			)
			(fill no)
			(layer "F.Fab")
		)
		(pad "1" smd rect
			(at 0 -0.9652 270)
			(size 1.397 1.143)
			(layers "F.Cu" "F.Mask" "F.Paste")
			(net "TPS74801_P1V5_C_IN")
		)
		(pad "2" smd rect
			(at 0 0.9652 270)
			(size 1.397 1.143)
			(layers "F.Cu" "F.Mask" "F.Paste")
			(net "GND")
		)
	)
	(footprint ""
		(layer "F.Cu")
		(at 289.687 -66.675 90)
		(property "Reference" "PR9000"
			(at 0 0 90)
			(layer "F.SilkS")
			(hide yes)
			(effects
				(font
					(size 1.27 1.27)
				)
			)
		)
		(property "Value" "0R2J-2-GP"
			(at 0.064008 -3.993896 90)
			(unlocked yes)
			(layer "F.Fab")
			(hide yes)
			(effects
				(font
					(size 1.016 1.016)
					(thickness 0.1524)
				)
			)
		)
		(property "Device Type" "R402H16"
			(at 0.064008 -5.517896 90)
			(unlocked yes)
			(layer "F.Fab")
			(hide yes)
			(effects
				(font
					(size 1.016 1.016)
					(thickness 0.1524)
				)
			)
		)
		(duplicate_pad_numbers_are_jumpers no)
		(fp_line
			(start 0.508 -0.9398)
			(end -0.508 -0.9398)
			(stroke
				(width 0.1524)
				(type default)
			)
			(layer "F.SilkS")
		)
		(fp_line
			(start -0.508 -0.9398)
			(end -0.508 0.9398)
			(stroke
				(width 0.1524)
				(type default)
			)
			(layer "F.SilkS")
		)
		(fp_rect
			(start -0.508 0.9398)
			(end 0.508 -0.9398)
			(stroke
				(width 0)
				(type default)
			)
			(fill no)
			(layer "F.CrtYd")
		)
		(fp_rect
			(start -0.508 0.9398)
			(end 0.508 -0.9398)
			(stroke
				(width 0)
				(type default)
			)
			(fill no)
			(layer "F.Fab")
		)
		(pad "1" smd custom
			(at 0 -0.4445 90)
			(size 0.1397 0.1397)
			(layers "F.Cu" "F.Mask" "F.Paste")
			(net "HSW_SCL1")
			(options
				(clearance outline)
				(anchor circle)
			)
			(primitives
				(gr_poly
					(pts
						(arc
							(start -0.1778 -0.2794)
							(mid -0.249642 -0.249642)
							(end -0.2794 -0.1778)
						)
						(arc
							(start -0.2794 0.1778)
							(mid -0.249642 0.249642)
							(end -0.1778 0.2794)
						)
						(arc
							(start 0.1778 0.2794)
							(mid 0.249642 0.249642)
							(end 0.2794 0.1778)
						)
						(arc
							(start 0.2794 -0.1778)
							(mid 0.249642 -0.249642)
							(end 0.1778 -0.2794)
						)
					)
					(width 0)
					(fill yes)
				)
			)
		)
		(pad "2" smd custom
			(at 0 0.4445 90)
			(size 0.1397 0.1397)
			(layers "F.Cu" "F.Mask" "F.Paste")
			(net "BMC_I2C_A_SCL")
			(options
				(clearance outline)
				(anchor circle)
			)
			(primitives
				(gr_poly
					(pts
						(arc
							(start -0.1778 -0.2794)
							(mid -0.249642 -0.249642)
							(end -0.2794 -0.1778)
						)
						(arc
							(start -0.2794 0.1778)
							(mid -0.249642 0.249642)
							(end -0.1778 0.2794)
						)
						(arc
							(start 0.1778 0.2794)
							(mid 0.249642 0.249642)
							(end 0.2794 0.1778)
						)
						(arc
							(start 0.2794 -0.1778)
							(mid 0.249642 -0.249642)
							(end 0.1778 -0.2794)
						)
					)
					(width 0)
					(fill yes)
				)
			)
		)
	)
	(footprint ""
		(layer "F.Cu")
		(at 93.072966 -63.119)
		(property "Reference" "SR675"
			(at 0 0 0)
			(layer "F.SilkS")
			(hide yes)
			(effects
				(font
					(size 1.27 1.27)
				)
			)
		)
		(property "Value" "4K7R2F-GP"
			(at 0.064008 -3.993896 0)
			(unlocked yes)
			(layer "F.Fab")
			(hide yes)
			(effects
				(font
					(size 1.016 1.016)
					(thickness 0.1524)
				)
			)
		)
		(property "Device Type" "R402H16"
			(at 0.064008 -5.517896 0)
			(unlocked yes)
			(layer "F.Fab")
			(hide yes)
			(effects
				(font
					(size 1.016 1.016)
					(thickness 0.1524)
				)
			)
		)
		(duplicate_pad_numbers_are_jumpers no)
		(fp_line
			(start -0.508 -0.9398)
			(end -0.508 0.9398)
			(stroke
				(width 0.1524)
				(type default)
			)
			(layer "F.SilkS")
		)
		(fp_line
			(start 0.508 -0.9398)
			(end -0.508 -0.9398)
			(stroke
				(width 0.1524)
				(type default)
			)
			(layer "F.SilkS")
		)
		(fp_rect
			(start -0.508 0.9398)
			(end 0.508 -0.9398)
			(stroke
				(width 0)
				(type default)
			)
			(fill no)
			(layer "F.CrtYd")
		)
		(fp_rect
			(start -0.508 0.9398)
			(end 0.508 -0.9398)
			(stroke
				(width 0)
				(type default)
			)
			(fill no)
			(layer "F.Fab")
		)
		(pad "1" smd custom
			(at 0 -0.4445)
			(size 0.1397 0.1397)
			(layers "F.Cu" "F.Mask" "F.Paste")
			(net "P1V8_C")
			(options
				(clearance outline)
				(anchor circle)
			)
			(primitives
				(gr_poly
					(pts
						(arc
							(start -0.1778 -0.2794)
							(mid -0.249642 -0.249642)
							(end -0.2794 -0.1778)
						)
						(arc
							(start -0.2794 0.1778)
							(mid -0.249642 0.249642)
							(end -0.1778 0.2794)
						)
						(arc
							(start 0.1778 0.2794)
							(mid 0.249642 0.249642)
							(end 0.2794 0.1778)
						)
						(arc
							(start 0.2794 -0.1778)
							(mid 0.249642 -0.249642)
							(end 0.1778 -0.2794)
						)
					)
					(width 0)
					(fill yes)
				)
			)
		)
		(pad "2" smd custom
			(at 0 0.4445)
			(size 0.1397 0.1397)
			(layers "F.Cu" "F.Mask" "F.Paste")
			(net "ICE1_TCK")
			(options
				(clearance outline)
				(anchor circle)
			)
			(primitives
				(gr_poly
					(pts
						(arc
							(start -0.1778 -0.2794)
							(mid -0.249642 -0.249642)
							(end -0.2794 -0.1778)
						)
						(arc
							(start -0.2794 0.1778)
							(mid -0.249642 0.249642)
							(end -0.1778 0.2794)
						)
						(arc
							(start 0.1778 0.2794)
							(mid 0.249642 0.249642)
							(end 0.2794 0.1778)
						)
						(arc
							(start 0.2794 -0.1778)
							(mid 0.249642 -0.249642)
							(end 0.1778 -0.2794)
						)
					)
					(width 0)
					(fill yes)
				)
			)
		)
	)
	(footprint ""
		(layer "F.Cu")
		(at 266.065 -179.07 90)
		(property "Reference" "R351"
			(at 0 0 90)
			(layer "F.SilkS")
			(hide yes)
			(effects
				(font
					(size 1.27 1.27)
				)
			)
		)
		(property "Value" "3K3R2F-2-GP"
			(at 0.064008 -3.993896 90)
			(unlocked yes)
			(layer "F.Fab")
			(hide yes)
			(effects
				(font
					(size 1.016 1.016)
					(thickness 0.1524)
				)
			)
		)
		(property "Device Type" "R402H16"
			(at 0.064008 -5.517896 90)
			(unlocked yes)
			(layer "F.Fab")
			(hide yes)
			(effects
				(font
					(size 1.016 1.016)
					(thickness 0.1524)
				)
			)
		)
		(duplicate_pad_numbers_are_jumpers no)
		(fp_line
			(start 0.508 -0.9398)
			(end -0.508 -0.9398)
			(stroke
				(width 0.1524)
				(type default)
			)
			(layer "F.SilkS")
		)
		(fp_line
			(start -0.508 -0.9398)
			(end -0.508 0.9398)
			(stroke
				(width 0.1524)
				(type default)
			)
			(layer "F.SilkS")
		)
		(fp_rect
			(start -0.508 0.9398)
			(end 0.508 -0.9398)
			(stroke
				(width 0)
				(type default)
			)
			(fill no)
			(layer "F.CrtYd")
		)
		(fp_rect
			(start -0.508 0.9398)
			(end 0.508 -0.9398)
			(stroke
				(width 0)
				(type default)
			)
			(fill no)
			(layer "F.Fab")
		)
		(pad "1" smd custom
			(at 0 -0.4445 90)
			(size 0.1397 0.1397)
			(layers "F.Cu" "F.Mask" "F.Paste")
			(net "P3V3_STBY")
			(options
				(clearance outline)
				(anchor circle)
			)
			(primitives
				(gr_poly
					(pts
						(arc
							(start -0.1778 -0.2794)
							(mid -0.249642 -0.249642)
							(end -0.2794 -0.1778)
						)
						(arc
							(start -0.2794 0.1778)
							(mid -0.249642 0.249642)
							(end -0.1778 0.2794)
						)
						(arc
							(start 0.1778 0.2794)
							(mid 0.249642 0.249642)
							(end 0.2794 0.1778)
						)
						(arc
							(start 0.2794 -0.1778)
							(mid 0.249642 -0.249642)
							(end 0.1778 -0.2794)
						)
					)
					(width 0)
					(fill yes)
				)
			)
		)
		(pad "2" smd custom
			(at 0 0.4445 90)
			(size 0.1397 0.1397)
			(layers "F.Cu" "F.Mask" "F.Paste")
			(net "ROMA3")
			(options
				(clearance outline)
				(anchor circle)
			)
			(primitives
				(gr_poly
					(pts
						(arc
							(start -0.1778 -0.2794)
							(mid -0.249642 -0.249642)
							(end -0.2794 -0.1778)
						)
						(arc
							(start -0.2794 0.1778)
							(mid -0.249642 0.249642)
							(end -0.1778 0.2794)
						)
						(arc
							(start 0.1778 0.2794)
							(mid 0.249642 0.249642)
							(end 0.2794 0.1778)
						)
						(arc
							(start 0.2794 -0.1778)
							(mid 0.249642 -0.249642)
							(end 0.1778 -0.2794)
						)
					)
					(width 0)
					(fill yes)
				)
			)
		)
	)
)
